(kicad_pcb
	(version 20260206)
	(generator "pcbnew")
	(generator_version "10.0")
	(general
		(thickness 1.6)
		(legacy_teardrops no)
	)
	(paper "A4")
	(title_block
		(title "v1-pdb — T6M_PDB_D_0927_0900.brd")
		(comment 1 "Open CloudServer (Microsoft) / footprints 316-317 of 321")
	)
	(layers
		(0 "F.Cu" signal "TOP")
		(4 "In1.Cu" signal "GND")
		(6 "In2.Cu" signal "IN1")
		(8 "In3.Cu" signal "VCC")
		(10 "In4.Cu" signal "VCC1")
		(12 "In5.Cu" signal "IN2")
		(14 "In6.Cu" signal "GND1")
		(2 "B.Cu" signal "BOTTOM")
		(9 "F.Adhes" user "F.Adhesive")
		(11 "B.Adhes" user "B.Adhesive")
		(13 "F.Paste" user "Package Geometry/Pastemask Top")
		(15 "B.Paste" user "Package Geometry/Pastemask Bottom")
		(5 "F.SilkS" user "Ref Des/Silkscreen Top")
		(7 "B.SilkS" user "Ref Des/Silkscreen Bottom")
		(1 "F.Mask" user "Board Geometry/Soldermask Top")
		(3 "B.Mask" user "Board Geometry/Soldermask Bottom")
		(17 "Dwgs.User" user "User.Drawings")
		(19 "Cmts.User" user "User.Comments")
		(21 "Eco1.User" user "User.Eco1")
		(23 "Eco2.User" user "User.Eco2")
		(25 "Edge.Cuts" user "Board Geometry/Outline")
		(27 "Margin" user)
		(31 "F.CrtYd" user "Package Geometry/Place Bound Top")
		(29 "B.CrtYd" user "Package Geometry/Place Bound Bottom")
		(35 "F.Fab" user "Ref Des/Assembly Top")
		(33 "B.Fab" user "Ref Des/Assembly Bottom")
	)
	(footprint ""
		(layer "B.Cu")
		(at 98.951288 -16.810228)
		(property "Reference" ""
			(at 0 0 0)
			(layer "B.SilkS")
			(hide yes)
			(effects
				(font
					(size 1.27 1.27)
				)
				(justify mirror)
			)
		)
		(property "Value" ""
			(at 0 0 0)
			(layer "B.Fab")
			(effects
				(font
					(size 1.27 1.27)
				)
				(justify mirror)
			)
		)
		(duplicate_pad_numbers_are_jumpers no)
		(fp_poly
			(pts
				(arc
					(start 1.4986 0)
					(mid -1.4986 0)
					(end 1.4986 0)
				)
			)
			(stroke
				(width 0)
				(type default)
			)
			(fill no)
			(layer "B.CrtYd")
		)
		(pad "1" smd circle
			(at 0 0 180)
			(size 0.9906 0.9906)
			(layers "B.Cu" "B.Mask" "B.Paste")
			(net "Net_1")
		)
		(zone
			(layer "B.Cu")
			(hatch none 0.5)
			(connect_pads
				(clearance 0)
			)
			(min_thickness 0.25)
			(keepout
				(tracks not_allowed)
				(vias allowed)
				(pads allowed)
				(copperpour not_allowed)
				(footprints allowed)
			)
			(placement
				(enabled no)
				(sheetname "")
			)
			(fill
				(thermal_gap 0.5)
				(thermal_bridge_width 0.5)
				(island_removal_mode 0)
			)
			(polygon
				(pts
					(arc
						(start 100.576888 -16.810228)
						(mid 97.325688 -16.810228)
						(end 100.576888 -16.810228)
					)
				)
			)
		)
	)
	(footprint ""
		(layer "B.Cu")
		(at 87.585804 -516.95858)
		(property "Reference" ""
			(at 0 0 0)
			(layer "B.SilkS")
			(hide yes)
			(effects
				(font
					(size 1.27 1.27)
				)
				(justify mirror)
			)
		)
		(property "Value" ""
			(at 0 0 0)
			(layer "B.Fab")
			(effects
				(font
					(size 1.27 1.27)
				)
				(justify mirror)
			)
		)
		(duplicate_pad_numbers_are_jumpers no)
		(fp_poly
			(pts
				(arc
					(start 1.4986 0)
					(mid -1.4986 0)
					(end 1.4986 0)
				)
			)
			(stroke
				(width 0)
				(type default)
			)
			(fill no)
			(layer "B.CrtYd")
		)
		(pad "1" smd circle
			(at 0 0 180)
			(size 0.9906 0.9906)
			(layers "B.Cu" "B.Mask" "B.Paste")
			(net "Net_2")
		)
		(zone
			(layer "B.Cu")
			(hatch none 0.5)
			(connect_pads
				(clearance 0)
			)
			(min_thickness 0.25)
			(keepout
				(tracks not_allowed)
				(vias allowed)
				(pads allowed)
				(copperpour not_allowed)
				(footprints allowed)
			)
			(placement
				(enabled no)
				(sheetname "")
			)
			(fill
				(thermal_gap 0.5)
				(thermal_bridge_width 0.5)
				(island_removal_mode 0)
			)
			(polygon
				(pts
					(arc
						(start 89.211404 -516.95858)
						(mid 85.960204 -516.95858)
						(end 89.211404 -516.95858)
					)
				)
			)
		)
	)
)
